# SCM (Grand Teton) — schematic netlist excerpt (pin names and nets, part order shuffled) for the footprints in the layout excerpt that follows; sources: Cadence DE-HDL packaged netlist, KiCad conversion of 12092022_DA0F0TMDCD0_F0T_Management_Board_D_brd_V3_OCP.brd

R880  Q_RES  33.2 1% CHIP  pkg 0402LF  page 12 : A = SMB_BMC_MM16_R5_SDA ; B = SMB_BMC_MM16_SDA
R462  Q_RES  4.7K 1% CHIP  pkg 0402LF  page 15 : A = P3V3_AUX ; B = SYS_BMC_PWRBTN_R1_N

(kicad_pcb
	(version 20260206)
	(generator "pcbnew")
	(generator_version "10.0")
	(general
		(thickness 1.6)
		(legacy_teardrops no)
	)
	(paper "A4")
	(title_block
		(title "12092022_DA0F0TMDCD0_F0T_Management_Board_D_brd_V3_OCP.brd")
		(comment 1 "Grand Teton / footprints 1121-1122 of 1440")
	)
	(layers
		(0 "F.Cu" signal "TOP")
		(4 "In1.Cu" signal "GND")
		(6 "In2.Cu" signal "IN1")
		(8 "In3.Cu" signal "GND1")
		(10 "In4.Cu" signal "IN2")
		(12 "In5.Cu" signal "VCC")
		(14 "In6.Cu" signal "VCC1")
		(16 "In7.Cu" signal "IN3")
		(18 "In8.Cu" signal "GND2")
		(20 "In9.Cu" signal "IN4")
		(22 "In10.Cu" signal "GND3")
		(2 "B.Cu" signal "BOTTOM")
		(9 "F.Adhes" user "F.Adhesive")
		(11 "B.Adhes" user "B.Adhesive")
		(13 "F.Paste" user "Package Geometry/Pastemask Top")
		(15 "B.Paste" user "Package Geometry/Pastemask Bottom")
		(5 "F.SilkS" user "Ref Des/Silkscreen Top")
		(7 "B.SilkS" user "Ref Des/Silkscreen Bottom")
		(1 "F.Mask" user "Board Geometry/Soldermask Top")
		(3 "B.Mask" user "Board Geometry/Soldermask Bottom")
		(17 "Dwgs.User" user "User.Drawings")
		(19 "Cmts.User" user "User.Comments")
		(21 "Eco1.User" user "User.Eco1")
		(23 "Eco2.User" user "User.Eco2")
		(25 "Edge.Cuts" user "Board Geometry/Outline")
		(27 "Margin" user)
		(31 "F.CrtYd" user "Package Geometry/Place Bound Top")
		(29 "B.CrtYd" user "Package Geometry/Place Bound Bottom")
		(35 "F.Fab" user "Ref Des/Assembly Top")
		(33 "B.Fab" user "Ref Des/Assembly Bottom")
	)
	(footprint ""
		(layer "B.Cu")
		(at 49.784 -28.829 -90)
		(property "Reference" "R880"
			(at 0 0 90)
			(layer "B.SilkS")
			(hide yes)
			(effects
				(font
					(size 1.27 1.27)
				)
				(justify mirror)
			)
		)
		(property "Value" ""
			(at 0 0 90)
			(layer "B.Fab")
			(effects
				(font
					(size 1.27 1.27)
				)
				(justify mirror)
			)
		)
		(duplicate_pad_numbers_are_jumpers no)
		(fp_line
			(start -0.7874 0.4064)
			(end 0.7874 0.4064)
			(stroke
				(width 0.1524)
				(type default)
			)
			(layer "B.SilkS")
		)
		(fp_line
			(start 0.7874 0.4064)
			(end 0.7874 -0.4064)
			(stroke
				(width 0.1524)
				(type default)
			)
			(layer "B.SilkS")
		)
		(fp_line
			(start -0.7874 -0.4064)
			(end -0.7874 0.4064)
			(stroke
				(width 0.1524)
				(type default)
			)
			(layer "B.SilkS")
		)
		(fp_line
			(start 0.7874 -0.4064)
			(end -0.7874 -0.4064)
			(stroke
				(width 0.1524)
				(type default)
			)
			(layer "B.SilkS")
		)
		(fp_line
			(start -0.67945 0.3048)
			(end -0.120396 0.3048)
			(stroke
				(width 0.1)
				(type default)
			)
			(layer "B.Fab")
		)
		(fp_line
			(start -0.120396 0.3048)
			(end -0.120396 0.2794)
			(stroke
				(width 0.1)
				(type default)
			)
			(layer "B.Fab")
		)
		(fp_line
			(start 0.12065 0.3048)
			(end 0.67945 0.3048)
			(stroke
				(width 0.1)
				(type default)
			)
			(layer "B.Fab")
		)
		(fp_line
			(start 0.67945 0.3048)
			(end 0.67945 -0.305054)
			(stroke
				(width 0.1)
				(type default)
			)
			(layer "B.Fab")
		)
		(fp_line
			(start -0.120396 0.2794)
			(end 0.12065 0.2794)
			(stroke
				(width 0.1)
				(type default)
			)
			(layer "B.Fab")
		)
		(fp_line
			(start 0.12065 0.2794)
			(end 0.12065 0.3048)
			(stroke
				(width 0.1)
				(type default)
			)
			(layer "B.Fab")
		)
		(fp_line
			(start -0.12065 -0.2794)
			(end -0.12065 -0.3048)
			(stroke
				(width 0.1)
				(type default)
			)
			(layer "B.Fab")
		)
		(fp_line
			(start 0.12065 -0.2794)
			(end -0.12065 -0.2794)
			(stroke
				(width 0.1)
				(type default)
			)
			(layer "B.Fab")
		)
		(fp_line
			(start -0.67945 -0.3048)
			(end -0.67945 0.3048)
			(stroke
				(width 0.1)
				(type default)
			)
			(layer "B.Fab")
		)
		(fp_line
			(start -0.12065 -0.3048)
			(end -0.67945 -0.3048)
			(stroke
				(width 0.1)
				(type default)
			)
			(layer "B.Fab")
		)
		(fp_line
			(start 0.12065 -0.305054)
			(end 0.12065 -0.2794)
			(stroke
				(width 0.1)
				(type default)
			)
			(layer "B.Fab")
		)
		(fp_line
			(start 0.67945 -0.305054)
			(end 0.12065 -0.305054)
			(stroke
				(width 0.1)
				(type default)
			)
			(layer "B.Fab")
		)
		(pad "1" smd circle
			(at 0.40005 0 90)
			(size 0 0)
			(layers "B.Cu" "B.Mask" "B.Paste")
			(net "SMB_BMC_MM16_R5_SDA")
		)
		(pad "2" smd circle
			(at -0.40005 0 90)
			(size 0 0)
			(layers "B.Cu" "B.Mask" "B.Paste")
			(net "SMB_BMC_MM16_SDA")
		)
	)
	(footprint ""
		(layer "B.Cu")
		(at 40.62222 -60.35294 -90)
		(property "Reference" "R462"
			(at 0 0 90)
			(layer "B.SilkS")
			(hide yes)
			(effects
				(font
					(size 1.27 1.27)
				)
				(justify mirror)
			)
		)
		(property "Value" ""
			(at 0 0 90)
			(layer "B.Fab")
			(effects
				(font
					(size 1.27 1.27)
				)
				(justify mirror)
			)
		)
		(duplicate_pad_numbers_are_jumpers no)
		(fp_line
			(start -0.7874 0.4064)
			(end 0.7874 0.4064)
			(stroke
				(width 0.1524)
				(type default)
			)
			(layer "B.SilkS")
		)
		(fp_line
			(start 0.7874 0.4064)
			(end 0.7874 -0.4064)
			(stroke
				(width 0.1524)
				(type default)
			)
			(layer "B.SilkS")
		)
		(fp_line
			(start -0.7874 -0.4064)
			(end -0.7874 0.4064)
			(stroke
				(width 0.1524)
				(type default)
			)
			(layer "B.SilkS")
		)
		(fp_line
			(start 0.7874 -0.4064)
			(end -0.7874 -0.4064)
			(stroke
				(width 0.1524)
				(type default)
			)
			(layer "B.SilkS")
		)
		(fp_line
			(start -0.67945 0.3048)
			(end -0.120396 0.3048)
			(stroke
				(width 0.1)
				(type default)
			)
			(layer "B.Fab")
		)
		(fp_line
			(start -0.120396 0.3048)
			(end -0.120396 0.2794)
			(stroke
				(width 0.1)
				(type default)
			)
			(layer "B.Fab")
		)
		(fp_line
			(start 0.12065 0.3048)
			(end 0.67945 0.3048)
			(stroke
				(width 0.1)
				(type default)
			)
			(layer "B.Fab")
		)
		(fp_line
			(start 0.67945 0.3048)
			(end 0.67945 -0.305054)
			(stroke
				(width 0.1)
				(type default)
			)
			(layer "B.Fab")
		)
		(fp_line
			(start -0.120396 0.2794)
			(end 0.12065 0.2794)
			(stroke
				(width 0.1)
				(type default)
			)
			(layer "B.Fab")
		)
		(fp_line
			(start 0.12065 0.2794)
			(end 0.12065 0.3048)
			(stroke
				(width 0.1)
				(type default)
			)
			(layer "B.Fab")
		)
		(fp_line
			(start -0.12065 -0.2794)
			(end -0.12065 -0.3048)
			(stroke
				(width 0.1)
				(type default)
			)
			(layer "B.Fab")
		)
		(fp_line
			(start 0.12065 -0.2794)
			(end -0.12065 -0.2794)
			(stroke
				(width 0.1)
				(type default)
			)
			(layer "B.Fab")
		)
		(fp_line
			(start -0.67945 -0.3048)
			(end -0.67945 0.3048)
			(stroke
				(width 0.1)
				(type default)
			)
			(layer "B.Fab")
		)
		(fp_line
			(start -0.12065 -0.3048)
			(end -0.67945 -0.3048)
			(stroke
				(width 0.1)
				(type default)
			)
			(layer "B.Fab")
		)
		(fp_line
			(start 0.12065 -0.305054)
			(end 0.12065 -0.2794)
			(stroke
				(width 0.1)
				(type default)
			)
			(layer "B.Fab")
		)
		(fp_line
			(start 0.67945 -0.305054)
			(end 0.12065 -0.305054)
			(stroke
				(width 0.1)
				(type default)
			)
			(layer "B.Fab")
		)
		(pad "1" smd circle
			(at 0.40005 0 90)
			(size 0 0)
			(layers "B.Cu" "B.Mask" "B.Paste")
			(net "P3V3_AUX")
		)
		(pad "2" smd circle
			(at -0.40005 0 90)
			(size 0 0)
			(layers "B.Cu" "B.Mask" "B.Paste")
			(net "SYS_BMC_PWRBTN_R1_N")
		)
	)
)
